(kicad_pcb
	(version 20260206)
	(generator "pcbnew")
	(generator_version "10.0")
	(general
		(thickness 1.6)
		(legacy_teardrops no)
	)
	(paper "A4")
	(title_block
		(title "12092022_DA0F0TMDCD0_F0T_Management_Board_D_brd_V3_OCP.brd")
		(comment 1 "Grand Teton / footprints 998-1003 of 1440")
	)
	(layers
		(0 "F.Cu" signal "TOP")
		(4 "In1.Cu" signal "GND")
		(6 "In2.Cu" signal "IN1")
		(8 "In3.Cu" signal "GND1")
		(10 "In4.Cu" signal "IN2")
		(12 "In5.Cu" signal "VCC")
		(14 "In6.Cu" signal "VCC1")
		(16 "In7.Cu" signal "IN3")
		(18 "In8.Cu" signal "GND2")
		(20 "In9.Cu" signal "IN4")
		(22 "In10.Cu" signal "GND3")
		(2 "B.Cu" signal "BOTTOM")
		(9 "F.Adhes" user "F.Adhesive")
		(11 "B.Adhes" user "B.Adhesive")
		(13 "F.Paste" user "Package Geometry/Pastemask Top")
		(15 "B.Paste" user "Package Geometry/Pastemask Bottom")
		(5 "F.SilkS" user "Ref Des/Silkscreen Top")
		(7 "B.SilkS" user "Ref Des/Silkscreen Bottom")
		(1 "F.Mask" user "Board Geometry/Soldermask Top")
		(3 "B.Mask" user "Board Geometry/Soldermask Bottom")
		(17 "Dwgs.User" user "User.Drawings")
		(19 "Cmts.User" user "User.Comments")
		(21 "Eco1.User" user "User.Eco1")
		(23 "Eco2.User" user "User.Eco2")
		(25 "Edge.Cuts" user "Board Geometry/Outline")
		(27 "Margin" user)
		(31 "F.CrtYd" user "Package Geometry/Place Bound Top")
		(29 "B.CrtYd" user "Package Geometry/Place Bound Bottom")
		(35 "F.Fab" user "Ref Des/Assembly Top")
		(33 "B.Fab" user "Ref Des/Assembly Bottom")
	)
	(footprint ""
		(layer "B.Cu")
		(at 59.109102 -50.71364 90)
		(property "Reference" "C79"
			(at 0 0 90)
			(layer "B.SilkS")
			(hide yes)
			(effects
				(font
					(size 1.27 1.27)
				)
				(justify mirror)
			)
		)
		(property "Value" ""
			(at 0 0 90)
			(layer "B.Fab")
			(effects
				(font
					(size 1.27 1.27)
				)
				(justify mirror)
			)
		)
		(duplicate_pad_numbers_are_jumpers no)
		(fp_line
			(start 0.7874 -0.4064)
			(end -0.7874 -0.4064)
			(stroke
				(width 0.1524)
				(type default)
			)
			(layer "B.SilkS")
		)
		(fp_line
			(start -0.7874 -0.4064)
			(end -0.7874 0.4064)
			(stroke
				(width 0.1524)
				(type default)
			)
			(layer "B.SilkS")
		)
		(fp_line
			(start 0.7874 0.4064)
			(end 0.7874 -0.4064)
			(stroke
				(width 0.1524)
				(type default)
			)
			(layer "B.SilkS")
		)
		(fp_line
			(start -0.7874 0.4064)
			(end 0.7874 0.4064)
			(stroke
				(width 0.1524)
				(type default)
			)
			(layer "B.SilkS")
		)
		(fp_line
			(start 0.67945 -0.305054)
			(end 0.12065 -0.305054)
			(stroke
				(width 0.1)
				(type default)
			)
			(layer "B.Fab")
		)
		(fp_line
			(start 0.12065 -0.305054)
			(end 0.12065 -0.2794)
			(stroke
				(width 0.1)
				(type default)
			)
			(layer "B.Fab")
		)
		(fp_line
			(start -0.12065 -0.3048)
			(end -0.67945 -0.3048)
			(stroke
				(width 0.1)
				(type default)
			)
			(layer "B.Fab")
		)
		(fp_line
			(start -0.67945 -0.3048)
			(end -0.67945 0.3048)
			(stroke
				(width 0.1)
				(type default)
			)
			(layer "B.Fab")
		)
		(fp_line
			(start 0.12065 -0.2794)
			(end -0.12065 -0.2794)
			(stroke
				(width 0.1)
				(type default)
			)
			(layer "B.Fab")
		)
		(fp_line
			(start -0.12065 -0.2794)
			(end -0.12065 -0.3048)
			(stroke
				(width 0.1)
				(type default)
			)
			(layer "B.Fab")
		)
		(fp_line
			(start 0.12065 0.2794)
			(end 0.12065 0.3048)
			(stroke
				(width 0.1)
				(type default)
			)
			(layer "B.Fab")
		)
		(fp_line
			(start -0.120396 0.2794)
			(end 0.12065 0.2794)
			(stroke
				(width 0.1)
				(type default)
			)
			(layer "B.Fab")
		)
		(fp_line
			(start 0.67945 0.3048)
			(end 0.67945 -0.305054)
			(stroke
				(width 0.1)
				(type default)
			)
			(layer "B.Fab")
		)
		(fp_line
			(start 0.12065 0.3048)
			(end 0.67945 0.3048)
			(stroke
				(width 0.1)
				(type default)
			)
			(layer "B.Fab")
		)
		(fp_line
			(start -0.120396 0.3048)
			(end -0.120396 0.2794)
			(stroke
				(width 0.1)
				(type default)
			)
			(layer "B.Fab")
		)
		(fp_line
			(start -0.67945 0.3048)
			(end -0.120396 0.3048)
			(stroke
				(width 0.1)
				(type default)
			)
			(layer "B.Fab")
		)
		(pad "1" smd circle
			(at 0.40005 0 270)
			(size 0 0)
			(layers "B.Cu" "B.Mask" "B.Paste")
			(net "P1V0_STBY_PE_VCC10A")
		)
		(pad "2" smd circle
			(at -0.40005 0 270)
			(size 0 0)
			(layers "B.Cu" "B.Mask" "B.Paste")
			(net "GND")
		)
	)
	(footprint ""
		(layer "B.Cu")
		(at 81.788 -59.055 90)
		(property "Reference" "C131"
			(at 0 0 90)
			(layer "B.SilkS")
			(hide yes)
			(effects
				(font
					(size 1.27 1.27)
				)
				(justify mirror)
			)
		)
		(property "Value" ""
			(at 0 0 90)
			(layer "B.Fab")
			(effects
				(font
					(size 1.27 1.27)
				)
				(justify mirror)
			)
		)
		(duplicate_pad_numbers_are_jumpers no)
		(fp_line
			(start 1.2954 -0.5842)
			(end -1.2954 -0.5842)
			(stroke
				(width 0.1524)
				(type default)
			)
			(layer "B.SilkS")
		)
		(fp_line
			(start 0 -0.5842)
			(end 0 0.5842)
			(stroke
				(width 0.1524)
				(type default)
			)
			(layer "B.SilkS")
		)
		(fp_line
			(start -1.2954 -0.5842)
			(end -1.2954 0.5842)
			(stroke
				(width 0.1524)
				(type default)
			)
			(layer "B.SilkS")
		)
		(fp_line
			(start 1.2954 0.5842)
			(end 1.2954 -0.5842)
			(stroke
				(width 0.1524)
				(type default)
			)
			(layer "B.SilkS")
		)
		(fp_line
			(start -1.2954 0.5842)
			(end 1.2954 0.5842)
			(stroke
				(width 0.1524)
				(type default)
			)
			(layer "B.SilkS")
		)
		(fp_line
			(start 0.8636 -0.4572)
			(end -0.8636 -0.4572)
			(stroke
				(width 0.1)
				(type default)
			)
			(layer "B.Fab")
		)
		(fp_line
			(start -0.8636 -0.4572)
			(end -0.8636 -0.4064)
			(stroke
				(width 0.1)
				(type default)
			)
			(layer "B.Fab")
		)
		(fp_line
			(start 1.1938 -0.4064)
			(end 0.8636 -0.4064)
			(stroke
				(width 0.1)
				(type default)
			)
			(layer "B.Fab")
		)
		(fp_line
			(start 0.8636 -0.4064)
			(end 0.8636 -0.4572)
			(stroke
				(width 0.1)
				(type default)
			)
			(layer "B.Fab")
		)
		(fp_line
			(start -0.8636 -0.4064)
			(end -1.1938 -0.4064)
			(stroke
				(width 0.1)
				(type default)
			)
			(layer "B.Fab")
		)
		(fp_line
			(start -1.1938 -0.4064)
			(end -1.1938 0.4064)
			(stroke
				(width 0.1)
				(type default)
			)
			(layer "B.Fab")
		)
		(fp_line
			(start 1.1938 0.4064)
			(end 1.1938 -0.4064)
			(stroke
				(width 0.1)
				(type default)
			)
			(layer "B.Fab")
		)
		(fp_line
			(start 0.8636 0.4064)
			(end 1.1938 0.4064)
			(stroke
				(width 0.1)
				(type default)
			)
			(layer "B.Fab")
		)
		(fp_line
			(start -0.8636 0.4064)
			(end -0.8636 0.4572)
			(stroke
				(width 0.1)
				(type default)
			)
			(layer "B.Fab")
		)
		(fp_line
			(start -1.1938 0.4064)
			(end -0.8636 0.4064)
			(stroke
				(width 0.1)
				(type default)
			)
			(layer "B.Fab")
		)
		(fp_line
			(start 0.8636 0.4572)
			(end 0.8636 0.4064)
			(stroke
				(width 0.1)
				(type default)
			)
			(layer "B.Fab")
		)
		(fp_line
			(start -0.8636 0.4572)
			(end 0.8636 0.4572)
			(stroke
				(width 0.1)
				(type default)
			)
			(layer "B.Fab")
		)
		(pad "1" smd rect
			(at 0.7366 0)
			(size 0.7112 0.8128)
			(layers "B.Cu" "B.Mask" "B.Paste")
			(net "P1V2_AUX")
		)
		(pad "2" smd rect
			(at -0.7366 0)
			(size 0.7112 0.8128)
			(layers "B.Cu" "B.Mask" "B.Paste")
			(net "GND")
		)
	)
	(footprint ""
		(layer "B.Cu")
		(at 70.650862 -65.406016 90)
		(property "Reference" "L10"
			(at 0 0 90)
			(layer "B.SilkS")
			(hide yes)
			(effects
				(font
					(size 1.27 1.27)
				)
				(justify mirror)
			)
		)
		(property "Value" ""
			(at 0 0 90)
			(layer "B.Fab")
			(effects
				(font
					(size 1.27 1.27)
				)
				(justify mirror)
			)
		)
		(duplicate_pad_numbers_are_jumpers no)
		(fp_line
			(start 1.27 -0.5842)
			(end -1.27 -0.5842)
			(stroke
				(width 0.1524)
				(type default)
			)
			(layer "B.SilkS")
		)
		(fp_line
			(start 1.27 -0.5588)
			(end 1.27 -0.5842)
			(stroke
				(width 0.1524)
				(type default)
			)
			(layer "B.SilkS")
		)
		(fp_line
			(start 1.27 0.5842)
			(end 1.27 -0.5842)
			(stroke
				(width 0.1524)
				(type default)
			)
			(layer "B.SilkS")
		)
		(fp_line
			(start 0.127 0.5842)
			(end 0.127 -0.5842)
			(stroke
				(width 0.1524)
				(type default)
			)
			(layer "B.SilkS")
		)
		(fp_line
			(start -0.127 0.5842)
			(end -0.127 -0.5842)
			(stroke
				(width 0.1524)
				(type default)
			)
			(layer "B.SilkS")
		)
		(fp_line
			(start -1.27 0.5842)
			(end -1.27 -0.5842)
			(stroke
				(width 0.1524)
				(type default)
			)
			(layer "B.SilkS")
		)
		(fp_line
			(start -1.27 0.5842)
			(end 1.27 0.5842)
			(stroke
				(width 0.1524)
				(type default)
			)
			(layer "B.SilkS")
		)
		(fp_line
			(start 0.9144 -0.508)
			(end -0.9144 -0.508)
			(stroke
				(width 0.1)
				(type default)
			)
			(layer "B.Fab")
		)
		(fp_line
			(start -0.9144 -0.508)
			(end -0.9144 -0.406654)
			(stroke
				(width 0.1)
				(type default)
			)
			(layer "B.Fab")
		)
		(fp_line
			(start 1.194308 -0.406654)
			(end 0.9144 -0.406654)
			(stroke
				(width 0.1)
				(type default)
			)
			(layer "B.Fab")
		)
		(fp_line
			(start 0.9144 -0.406654)
			(end 0.9144 -0.508)
			(stroke
				(width 0.1)
				(type default)
			)
			(layer "B.Fab")
		)
		(fp_line
			(start -0.9144 -0.406654)
			(end -1.1938 -0.406654)
			(stroke
				(width 0.1)
				(type default)
			)
			(layer "B.Fab")
		)
		(fp_line
			(start -1.1938 -0.406654)
			(end -1.1938 0.4064)
			(stroke
				(width 0.1)
				(type default)
			)
			(layer "B.Fab")
		)
		(fp_line
			(start -0.9144 0.4064)
			(end -0.9144 0.508)
			(stroke
				(width 0.1)
				(type default)
			)
			(layer "B.Fab")
		)
		(fp_line
			(start -1.1938 0.4064)
			(end -0.9144 0.4064)
			(stroke
				(width 0.1)
				(type default)
			)
			(layer "B.Fab")
		)
		(fp_line
			(start 1.194308 0.406654)
			(end 1.194308 -0.406654)
			(stroke
				(width 0.1)
				(type default)
			)
			(layer "B.Fab")
		)
		(fp_line
			(start 0.9144 0.406654)
			(end 1.194308 0.406654)
			(stroke
				(width 0.1)
				(type default)
			)
			(layer "B.Fab")
		)
		(fp_line
			(start 0.9144 0.508)
			(end 0.9144 0.406654)
			(stroke
				(width 0.1)
				(type default)
			)
			(layer "B.Fab")
		)
		(fp_line
			(start -0.9144 0.508)
			(end 0.9144 0.508)
			(stroke
				(width 0.1)
				(type default)
			)
			(layer "B.Fab")
		)
		(pad "1" smd rect
			(at 0.7366 0)
			(size 0.7112 0.8128)
			(layers "B.Cu" "B.Mask" "B.Paste")
			(net "P1V8_AUX")
		)
		(pad "2" smd rect
			(at -0.7366 0)
			(size 0.7112 0.8128)
			(layers "B.Cu" "B.Mask" "B.Paste")
			(net "P1V8_STBY_PE_VCC18A")
		)
	)
	(footprint ""
		(layer "B.Cu")
		(at 85.32241 -28.627832)
		(property "Reference" "R12"
			(at 0 0 0)
			(layer "B.SilkS")
			(hide yes)
			(effects
				(font
					(size 1.27 1.27)
				)
				(justify mirror)
			)
		)
		(property "Value" ""
			(at 0 0 0)
			(layer "B.Fab")
			(effects
				(font
					(size 1.27 1.27)
				)
				(justify mirror)
			)
		)
		(duplicate_pad_numbers_are_jumpers no)
		(fp_line
			(start -0.7874 -0.4064)
			(end -0.7874 0.4064)
			(stroke
				(width 0.1524)
				(type default)
			)
			(layer "B.SilkS")
		)
		(fp_line
			(start -0.7874 0.4064)
			(end 0.7874 0.4064)
			(stroke
				(width 0.1524)
				(type default)
			)
			(layer "B.SilkS")
		)
		(fp_line
			(start 0.7874 -0.4064)
			(end -0.7874 -0.4064)
			(stroke
				(width 0.1524)
				(type default)
			)
			(layer "B.SilkS")
		)
		(fp_line
			(start 0.7874 0.4064)
			(end 0.7874 -0.4064)
			(stroke
				(width 0.1524)
				(type default)
			)
			(layer "B.SilkS")
		)
		(fp_line
			(start -0.67945 -0.3048)
			(end -0.67945 0.3048)
			(stroke
				(width 0.1)
				(type default)
			)
			(layer "B.Fab")
		)
		(fp_line
			(start -0.67945 0.3048)
			(end -0.120396 0.3048)
			(stroke
				(width 0.1)
				(type default)
			)
			(layer "B.Fab")
		)
		(fp_line
			(start -0.12065 -0.3048)
			(end -0.67945 -0.3048)
			(stroke
				(width 0.1)
				(type default)
			)
			(layer "B.Fab")
		)
		(fp_line
			(start -0.12065 -0.2794)
			(end -0.12065 -0.3048)
			(stroke
				(width 0.1)
				(type default)
			)
			(layer "B.Fab")
		)
		(fp_line
			(start -0.120396 0.2794)
			(end 0.12065 0.2794)
			(stroke
				(width 0.1)
				(type default)
			)
			(layer "B.Fab")
		)
		(fp_line
			(start -0.120396 0.3048)
			(end -0.120396 0.2794)
			(stroke
				(width 0.1)
				(type default)
			)
			(layer "B.Fab")
		)
		(fp_line
			(start 0.12065 -0.305054)
			(end 0.12065 -0.2794)
			(stroke
				(width 0.1)
				(type default)
			)
			(layer "B.Fab")
		)
		(fp_line
			(start 0.12065 -0.2794)
			(end -0.12065 -0.2794)
			(stroke
				(width 0.1)
				(type default)
			)
			(layer "B.Fab")
		)
		(fp_line
			(start 0.12065 0.2794)
			(end 0.12065 0.3048)
			(stroke
				(width 0.1)
				(type default)
			)
			(layer "B.Fab")
		)
		(fp_line
			(start 0.12065 0.3048)
			(end 0.67945 0.3048)
			(stroke
				(width 0.1)
				(type default)
			)
			(layer "B.Fab")
		)
		(fp_line
			(start 0.67945 -0.305054)
			(end 0.12065 -0.305054)
			(stroke
				(width 0.1)
				(type default)
			)
			(layer "B.Fab")
		)
		(fp_line
			(start 0.67945 0.3048)
			(end 0.67945 -0.305054)
			(stroke
				(width 0.1)
				(type default)
			)
			(layer "B.Fab")
		)
		(pad "1" smd circle
			(at 0.40005 0 180)
			(size 0 0)
			(layers "B.Cu" "B.Mask" "B.Paste")
			(net "P3V3_AUX")
		)
		(pad "2" smd circle
			(at -0.40005 0 180)
			(size 0 0)
			(layers "B.Cu" "B.Mask" "B.Paste")
			(net "FRU_E0")
		)
	)
	(footprint ""
		(layer "B.Cu")
		(at 56.861964 -71.064882 180)
		(property "Reference" "C282"
			(at 0 0 0)
			(layer "B.SilkS")
			(hide yes)
			(effects
				(font
					(size 1.27 1.27)
				)
				(justify mirror)
			)
		)
		(property "Value" ""
			(at 0 0 0)
			(layer "B.Fab")
			(effects
				(font
					(size 1.27 1.27)
				)
				(justify mirror)
			)
		)
		(duplicate_pad_numbers_are_jumpers no)
		(fp_line
			(start 0.7874 0.4064)
			(end 0.7874 -0.4064)
			(stroke
				(width 0.1524)
				(type default)
			)
			(layer "B.SilkS")
		)
		(fp_line
			(start 0.7874 -0.4064)
			(end -0.7874 -0.4064)
			(stroke
				(width 0.1524)
				(type default)
			)
			(layer "B.SilkS")
		)
		(fp_line
			(start -0.7874 0.4064)
			(end 0.7874 0.4064)
			(stroke
				(width 0.1524)
				(type default)
			)
			(layer "B.SilkS")
		)
		(fp_line
			(start -0.7874 -0.4064)
			(end -0.7874 0.4064)
			(stroke
				(width 0.1524)
				(type default)
			)
			(layer "B.SilkS")
		)
		(fp_line
			(start 0.67945 0.3048)
			(end 0.67945 -0.305054)
			(stroke
				(width 0.1)
				(type default)
			)
			(layer "B.Fab")
		)
		(fp_line
			(start 0.67945 -0.305054)
			(end 0.12065 -0.305054)
			(stroke
				(width 0.1)
				(type default)
			)
			(layer "B.Fab")
		)
		(fp_line
			(start 0.12065 0.3048)
			(end 0.67945 0.3048)
			(stroke
				(width 0.1)
				(type default)
			)
			(layer "B.Fab")
		)
		(fp_line
			(start 0.12065 0.2794)
			(end 0.12065 0.3048)
			(stroke
				(width 0.1)
				(type default)
			)
			(layer "B.Fab")
		)
		(fp_line
			(start 0.12065 -0.2794)
			(end -0.12065 -0.2794)
			(stroke
				(width 0.1)
				(type default)
			)
			(layer "B.Fab")
		)
		(fp_line
			(start 0.12065 -0.305054)
			(end 0.12065 -0.2794)
			(stroke
				(width 0.1)
				(type default)
			)
			(layer "B.Fab")
		)
		(fp_line
			(start -0.120396 0.3048)
			(end -0.120396 0.2794)
			(stroke
				(width 0.1)
				(type default)
			)
			(layer "B.Fab")
		)
		(fp_line
			(start -0.120396 0.2794)
			(end 0.12065 0.2794)
			(stroke
				(width 0.1)
				(type default)
			)
			(layer "B.Fab")
		)
		(fp_line
			(start -0.12065 -0.2794)
			(end -0.12065 -0.3048)
			(stroke
				(width 0.1)
				(type default)
			)
			(layer "B.Fab")
		)
		(fp_line
			(start -0.12065 -0.3048)
			(end -0.67945 -0.3048)
			(stroke
				(width 0.1)
				(type default)
			)
			(layer "B.Fab")
		)
		(fp_line
			(start -0.67945 0.3048)
			(end -0.120396 0.3048)
			(stroke
				(width 0.1)
				(type default)
			)
			(layer "B.Fab")
		)
		(fp_line
			(start -0.67945 -0.3048)
			(end -0.67945 0.3048)
			(stroke
				(width 0.1)
				(type default)
			)
			(layer "B.Fab")
		)
		(pad "1" smd circle
			(at 0.40005 0)
			(size 0 0)
			(layers "B.Cu" "B.Mask" "B.Paste")
			(net "ADCVREFEXT0")
		)
		(pad "2" smd circle
			(at -0.40005 0)
			(size 0 0)
			(layers "B.Cu" "B.Mask" "B.Paste")
			(net "GND")
		)
	)
	(footprint ""
		(layer "B.Cu")
		(at 80.755744 -37.559488 90)
		(property "Reference" "R351"
			(at 0 0 90)
			(layer "B.SilkS")
			(hide yes)
			(effects
				(font
					(size 1.27 1.27)
				)
				(justify mirror)
			)
		)
		(property "Value" ""
			(at 0 0 90)
			(layer "B.Fab")
			(effects
				(font
					(size 1.27 1.27)
				)
				(justify mirror)
			)
		)
		(duplicate_pad_numbers_are_jumpers no)
		(fp_line
			(start 0.7874 -0.4064)
			(end -0.7874 -0.4064)
			(stroke
				(width 0.1524)
				(type default)
			)
			(layer "B.SilkS")
		)
		(fp_line
			(start -0.7874 -0.4064)
			(end -0.7874 0.4064)
			(stroke
				(width 0.1524)
				(type default)
			)
			(layer "B.SilkS")
		)
		(fp_line
			(start 0.7874 0.4064)
			(end 0.7874 -0.4064)
			(stroke
				(width 0.1524)
				(type default)
			)
			(layer "B.SilkS")
		)
		(fp_line
			(start -0.7874 0.4064)
			(end 0.7874 0.4064)
			(stroke
				(width 0.1524)
				(type default)
			)
			(layer "B.SilkS")
		)
		(fp_line
			(start 0.67945 -0.305054)
			(end 0.12065 -0.305054)
			(stroke
				(width 0.1)
				(type default)
			)
			(layer "B.Fab")
		)
		(fp_line
			(start 0.12065 -0.305054)
			(end 0.12065 -0.2794)
			(stroke
				(width 0.1)
				(type default)
			)
			(layer "B.Fab")
		)
		(fp_line
			(start -0.12065 -0.3048)
			(end -0.67945 -0.3048)
			(stroke
				(width 0.1)
				(type default)
			)
			(layer "B.Fab")
		)
		(fp_line
			(start -0.67945 -0.3048)
			(end -0.67945 0.3048)
			(stroke
				(width 0.1)
				(type default)
			)
			(layer "B.Fab")
		)
		(fp_line
			(start 0.12065 -0.2794)
			(end -0.12065 -0.2794)
			(stroke
				(width 0.1)
				(type default)
			)
			(layer "B.Fab")
		)
		(fp_line
			(start -0.12065 -0.2794)
			(end -0.12065 -0.3048)
			(stroke
				(width 0.1)
				(type default)
			)
			(layer "B.Fab")
		)
		(fp_line
			(start 0.12065 0.2794)
			(end 0.12065 0.3048)
			(stroke
				(width 0.1)
				(type default)
			)
			(layer "B.Fab")
		)
		(fp_line
			(start -0.120396 0.2794)
			(end 0.12065 0.2794)
			(stroke
				(width 0.1)
				(type default)
			)
			(layer "B.Fab")
		)
		(fp_line
			(start 0.67945 0.3048)
			(end 0.67945 -0.305054)
			(stroke
				(width 0.1)
				(type default)
			)
			(layer "B.Fab")
		)
		(fp_line
			(start 0.12065 0.3048)
			(end 0.67945 0.3048)
			(stroke
				(width 0.1)
				(type default)
			)
			(layer "B.Fab")
		)
		(fp_line
			(start -0.120396 0.3048)
			(end -0.120396 0.2794)
			(stroke
				(width 0.1)
				(type default)
			)
			(layer "B.Fab")
		)
		(fp_line
			(start -0.67945 0.3048)
			(end -0.120396 0.3048)
			(stroke
				(width 0.1)
				(type default)
			)
			(layer "B.Fab")
		)
		(pad "1" smd circle
			(at 0.40005 0 270)
			(size 0 0)
			(layers "B.Cu" "B.Mask" "B.Paste")
			(net "M_BMC_DDR4_MA<0>")
		)
		(pad "2" smd circle
			(at -0.40005 0 270)
			(size 0 0)
			(layers "B.Cu" "B.Mask" "B.Paste")
			(net "P1V2_AUX")
		)
	)
)
